(kicad_pcb
	(version 20241229)
	(generator "pcbnew")
	(generator_version "9.0")
	(general
		(thickness 1.258)
		(legacy_teardrops no)
	)
	(paper "A4")
	(title_block
		(date "2024-05-27")
		(rev "1.1.2")
		(comment 9 "footprint 28 of 64 (J1), pads 101-197 of 262")
	)
	(layers
		(0 "F.Cu" signal)
		(4 "In1.Cu" power)
		(6 "In2.Cu" power)
		(8 "In3.Cu" signal)
		(10 "In4.Cu" signal)
		(2 "B.Cu" signal)
		(9 "F.Adhes" user "F.Adhesive")
		(11 "B.Adhes" user "B.Adhesive")
		(13 "F.Paste" user)
		(15 "B.Paste" user)
		(5 "F.SilkS" user "F.Silkscreen")
		(7 "B.SilkS" user "B.Silkscreen")
		(1 "F.Mask" user)
		(3 "B.Mask" user)
		(17 "Dwgs.User" user "User.Drawings")
		(19 "Cmts.User" user "User.Comments")
		(21 "Eco1.User" user "User.Eco1")
		(23 "Eco2.User" user "User.Eco2")
		(25 "Edge.Cuts" user)
		(27 "Margin" user)
		(31 "F.CrtYd" user "F.Courtyard")
		(29 "B.CrtYd" user "B.Courtyard")
		(35 "F.Fab" user)
		(33 "B.Fab" user)
	)
	(footprint "antmicro-footprints:PCB-Edge_SODIMM_2x130_DDR4"
		(locked yes)
		(layer "F.Cu")
		(at 100 100)
		(property "Reference" "J1"
			(at 0 -4.2 0)
			(layer "F.SilkS")
			(hide yes)
			(effects
				(font
					(size 0.7 0.7)
					(thickness 0.15)
				)
				(justify left bottom)
			)
		)
		(property "Value" "PCB-Edge_SODIMM_2x130_DDR4"
			(at 0 1 0)
			(layer "F.Fab")
			(effects
				(font
					(size 0.7 0.7)
					(thickness 0.15)
				)
				(justify left bottom)
			)
		)
		(property "Description" "DDR SO-DIMM PCB Edge"
			(at 0 0 0)
			(layer "F.Fab")
			(hide yes)
			(effects
				(font
					(size 1.27 1.27)
					(thickness 0.15)
				)
			)
		)
		(property "Author" "Antmicro"
			(at 0 0 0)
			(layer "F.Fab")
			(hide yes)
			(effects
				(font
					(size 1 1)
					(thickness 0.15)
				)
			)
		)
		(property "License" "Apache-2.0"
			(at 0 0 0)
			(layer "F.Fab")
			(hide yes)
			(effects
				(font
					(size 1 1)
					(thickness 0.15)
				)
			)
		)
		(property "MPN" ""
			(at 0 0 0)
			(layer "F.Fab")
			(hide yes)
			(effects
				(font
					(size 1 1)
					(thickness 0.15)
				)
			)
		)
		(property "Manufacturer" ""
			(at 0 0 0)
			(layer "F.Fab")
			(hide yes)
			(effects
				(font
					(size 1 1)
					(thickness 0.15)
				)
			)
		)
		(property "Public" "False"
			(at 0 0 0)
			(layer "F.Fab")
			(hide yes)
			(effects
				(font
					(size 1 1)
					(thickness 0.15)
				)
			)
		)
		(sheetname "SODIMM")
		(sheetfile "sodim.kicad_sch")
		(attr exclude_from_pos_files exclude_from_bom)
		(pad "99" smd rect
			(at 25.925 -1.301)
			(size 0.35 2.5)
			(layers "F.Cu" "F.Mask")
			(net 51 "1V1_SYS")
			(pinfunction "99")
			(pintype "passive")
		)
		(pad "100" smd rect
			(at 26.175 -1.301)
			(size 0.35 2.5)
			(layers "B.Cu" "B.Mask")
			(net 115 "unconnected-(J1-Pad100)")
			(pinfunction "100")
			(pintype "passive+no_connect")
		)
		(pad "101" smd rect
			(at 26.425 -1.301)
			(size 0.35 2.5)
			(layers "F.Cu" "F.Mask")
			(net 51 "1V1_SYS")
			(pinfunction "101")
			(pintype "passive")
		)
		(pad "102" smd rect
			(at 26.675 -1.301)
			(size 0.35 2.5)
			(layers "B.Cu" "B.Mask")
			(net 116 "unconnected-(J1-Pad102)")
			(pinfunction "102")
			(pintype "passive+no_connect")
		)
		(pad "103" smd rect
			(at 26.925 -1.301)
			(size 0.35 2.5)
			(layers "F.Cu" "F.Mask")
			(net 51 "1V1_SYS")
			(pinfunction "103")
			(pintype "passive")
		)
		(pad "104" smd rect
			(at 27.175 -1.301)
			(size 0.35 2.5)
			(layers "B.Cu" "B.Mask")
			(net 117 "unconnected-(J1-Pad104)")
			(pinfunction "104")
			(pintype "passive+no_connect")
		)
		(pad "105" smd rect
			(at 27.425 -1.301)
			(size 0.35 2.5)
			(layers "F.Cu" "F.Mask")
			(net 51 "1V1_SYS")
			(pinfunction "105")
			(pintype "passive")
		)
		(pad "106" smd rect
			(at 27.675 -1.301)
			(size 0.35 2.5)
			(layers "B.Cu" "B.Mask")
			(net 118 "unconnected-(J1-Pad106)")
			(pinfunction "106")
			(pintype "passive+no_connect")
		)
		(pad "107" smd rect
			(at 27.925 -1.301)
			(size 0.35 2.5)
			(layers "F.Cu" "F.Mask")
			(net 51 "1V1_SYS")
			(pinfunction "107")
			(pintype "passive")
		)
		(pad "108" smd rect
			(at 28.175 -1.301)
			(size 0.35 2.5)
			(layers "B.Cu" "B.Mask")
			(net 119 "unconnected-(J1-Pad108)")
			(pinfunction "108")
			(pintype "passive+no_connect")
		)
		(pad "109" smd rect
			(at 28.425 -1.301)
			(size 0.35 2.5)
			(layers "F.Cu" "F.Mask")
			(net 120 "unconnected-(J1-Pad109)")
			(pinfunction "109")
			(pintype "passive+no_connect")
		)
		(pad "110" smd rect
			(at 28.675 -1.301)
			(size 0.35 2.5)
			(layers "B.Cu" "B.Mask")
			(net 121 "unconnected-(J1-Pad110)")
			(pinfunction "110")
			(pintype "passive+no_connect")
		)
		(pad "111" smd rect
			(at 28.925 -1.301)
			(size 0.35 2.5)
			(layers "F.Cu" "F.Mask")
			(net 122 "unconnected-(J1-Pad111)")
			(pinfunction "111")
			(pintype "passive+no_connect")
		)
		(pad "112" smd rect
			(at 29.175 -1.301)
			(size 0.35 2.5)
			(layers "B.Cu" "B.Mask")
			(net 123 "unconnected-(J1-Pad112)")
			(pinfunction "112")
			(pintype "passive+no_connect")
		)
		(pad "113" smd rect
			(at 29.425 -1.301)
			(size 0.35 2.5)
			(layers "F.Cu" "F.Mask")
			(net 124 "unconnected-(J1-Pad113)")
			(pinfunction "113")
			(pintype "passive+no_connect")
		)
		(pad "114" smd rect
			(at 29.675 -1.301)
			(size 0.35 2.5)
			(layers "B.Cu" "B.Mask")
			(net 125 "unconnected-(J1-Pad114)")
			(pinfunction "114")
			(pintype "passive+no_connect")
		)
		(pad "115" smd rect
			(at 29.925 -1.301)
			(size 0.35 2.5)
			(layers "F.Cu" "F.Mask")
			(net 126 "unconnected-(J1-Pad115)")
			(pinfunction "115")
			(pintype "passive+no_connect")
		)
		(pad "116" smd rect
			(at 30.175 -1.301)
			(size 0.35 2.5)
			(layers "B.Cu" "B.Mask")
			(net 50 "1V8_SYS")
			(pinfunction "116")
			(pintype "passive")
		)
		(pad "117" smd rect
			(at 30.425 -1.301)
			(size 0.35 2.5)
			(layers "F.Cu" "F.Mask")
			(net 127 "unconnected-(J1-Pad117)")
			(pinfunction "117")
			(pintype "passive+no_connect")
		)
		(pad "118" smd rect
			(at 30.675 -1.301)
			(size 0.35 2.5)
			(layers "B.Cu" "B.Mask")
			(net 50 "1V8_SYS")
			(pinfunction "118")
			(pintype "passive")
		)
		(pad "119" smd rect
			(at 30.925 -1.301)
			(size 0.35 2.5)
			(layers "F.Cu" "F.Mask")
			(net 128 "unconnected-(J1-Pad119)")
			(pinfunction "119")
			(pintype "passive+no_connect")
		)
		(pad "120" smd rect
			(at 31.175 -1.301)
			(size 0.35 2.5)
			(layers "B.Cu" "B.Mask")
			(net 50 "1V8_SYS")
			(pinfunction "120")
			(pintype "passive")
		)
		(pad "121" smd rect
			(at 31.425 -1.301)
			(size 0.35 2.5)
			(layers "F.Cu" "F.Mask")
			(net 129 "unconnected-(J1-Pad121)")
			(pinfunction "121")
			(pintype "passive+no_connect")
		)
		(pad "122" smd rect
			(at 31.675 -1.301)
			(size 0.35 2.5)
			(layers "B.Cu" "B.Mask")
			(net 50 "1V8_SYS")
			(pinfunction "122")
			(pintype "passive")
		)
		(pad "123" smd rect
			(at 31.925 -1.301)
			(size 0.35 2.5)
			(layers "F.Cu" "F.Mask")
			(net 130 "unconnected-(J1-Pad123)")
			(pinfunction "123")
			(pintype "passive+no_connect")
		)
		(pad "124" smd rect
			(at 32.173 -1.301)
			(size 0.35 2.5)
			(layers "B.Cu" "B.Mask")
			(net 50 "1V8_SYS")
			(pinfunction "124")
			(pintype "passive")
		)
		(pad "125" smd rect
			(at 32.423 -1.301)
			(size 0.35 2.5)
			(layers "F.Cu" "F.Mask")
			(net 131 "unconnected-(J1-Pad125)")
			(pinfunction "125")
			(pintype "passive+no_connect")
		)
		(pad "126" smd rect
			(at 32.673 -1.301)
			(size 0.35 2.5)
			(layers "B.Cu" "B.Mask")
			(net 132 "unconnected-(J1-Pad126)")
			(pinfunction "126")
			(pintype "passive+no_connect")
		)
		(pad "127" smd rect
			(at 32.923 -1.301)
			(size 0.35 2.5)
			(layers "F.Cu" "F.Mask")
			(net 12 "SDA")
			(pinfunction "127")
			(pintype "passive")
		)
		(pad "128" smd rect
			(at 33.173 -1.301)
			(size 0.35 2.5)
			(layers "B.Cu" "B.Mask")
			(net 133 "unconnected-(J1-Pad128)")
			(pinfunction "128")
			(pintype "passive+no_connect")
		)
		(pad "129" smd rect
			(at 33.423 -1.301)
			(size 0.35 2.5)
			(layers "F.Cu" "F.Mask")
			(net 13 "SCL")
			(pinfunction "129")
			(pintype "passive")
		)
		(pad "130" smd rect
			(at 33.673 -1.301)
			(size 0.35 2.5)
			(layers "B.Cu" "B.Mask")
			(net 134 "unconnected-(J1-Pad130)")
			(pinfunction "130")
			(pintype "passive+no_connect")
		)
		(pad "131" smd rect
			(at 33.923 -1.301)
			(size 0.35 2.5)
			(layers "F.Cu" "F.Mask")
			(net 135 "unconnected-(J1-Pad131)")
			(pinfunction "131")
			(pintype "passive+no_connect")
		)
		(pad "132" smd rect
			(at 34.173 -1.301)
			(size 0.35 2.5)
			(layers "B.Cu" "B.Mask")
			(net 136 "unconnected-(J1-Pad132)")
			(pinfunction "132")
			(pintype "passive+no_connect")
		)
		(pad "133" smd rect
			(at 34.423 -1.301)
			(size 0.35 2.5)
			(layers "F.Cu" "F.Mask")
			(net 137 "unconnected-(J1-Pad133)")
			(pinfunction "133")
			(pintype "passive+no_connect")
		)
		(pad "134" smd rect
			(at 34.673 -1.301)
			(size 0.35 2.5)
			(layers "B.Cu" "B.Mask")
			(net 138 "unconnected-(J1-Pad134)")
			(pinfunction "134")
			(pintype "passive+no_connect")
		)
		(pad "135" smd rect
			(at 34.923 -1.301)
			(size 0.35 2.5)
			(layers "F.Cu" "F.Mask")
			(net 139 "unconnected-(J1-Pad135)")
			(pinfunction "135")
			(pintype "passive+no_connect")
		)
		(pad "136" smd rect
			(at 35.173 -1.301)
			(size 0.35 2.5)
			(layers "B.Cu" "B.Mask")
			(net 140 "unconnected-(J1-Pad136)")
			(pinfunction "136")
			(pintype "passive+no_connect")
		)
		(pad "137" smd rect
			(at 35.423 -1.301)
			(size 0.35 2.5)
			(layers "F.Cu" "F.Mask")
			(net 141 "unconnected-(J1-Pad137)")
			(pinfunction "137")
			(pintype "passive+no_connect")
		)
		(pad "138" smd rect
			(at 35.673 -1.301)
			(size 0.35 2.5)
			(layers "B.Cu" "B.Mask")
			(net 142 "unconnected-(J1-Pad138)")
			(pinfunction "138")
			(pintype "passive+no_connect")
		)
		(pad "139" smd rect
			(at 35.923 -1.301)
			(size 0.35 2.5)
			(layers "F.Cu" "F.Mask")
			(net 143 "unconnected-(J1-Pad139)")
			(pinfunction "139")
			(pintype "passive+no_connect")
		)
		(pad "140" smd rect
			(at 36.173 -1.301)
			(size 0.35 2.5)
			(layers "B.Cu" "B.Mask")
			(net 144 "unconnected-(J1-Pad140)")
			(pinfunction "140")
			(pintype "passive+no_connect")
		)
		(pad "141" smd rect
			(at 36.423 -1.301)
			(size 0.35 2.5)
			(layers "F.Cu" "F.Mask")
			(net 145 "unconnected-(J1-Pad141)")
			(pinfunction "141")
			(pintype "passive+no_connect")
		)
		(pad "142" smd rect
			(at 36.673 -1.301)
			(size 0.35 2.5)
			(layers "B.Cu" "B.Mask")
			(net 146 "unconnected-(J1-Pad142)")
			(pinfunction "142")
			(pintype "passive+no_connect")
		)
		(pad "143" smd rect
			(at 36.923 -1.301)
			(size 0.35 2.5)
			(layers "F.Cu" "F.Mask")
			(net 147 "unconnected-(J1-Pad143)")
			(pinfunction "143")
			(pintype "passive+no_connect")
		)
		(pad "144" smd rect
			(at 37.173 -1.301)
			(size 0.35 2.5)
			(layers "B.Cu" "B.Mask")
			(net 148 "unconnected-(J1-Pad144)")
			(pinfunction "144")
			(pintype "passive+no_connect")
		)
		(pad "145" smd rect
			(at 39.423 -1.301)
			(size 0.35 2.5)
			(layers "F.Cu" "F.Mask")
			(net 149 "unconnected-(J1-Pad145)")
			(pinfunction "145")
			(pintype "passive+no_connect")
		)
		(pad "146" smd rect
			(at 39.673 -1.301)
			(size 0.35 2.5)
			(layers "B.Cu" "B.Mask")
			(net 150 "unconnected-(J1-Pad146)")
			(pinfunction "146")
			(pintype "passive+no_connect")
		)
		(pad "147" smd rect
			(at 39.923 -1.301)
			(size 0.35 2.5)
			(layers "F.Cu" "F.Mask")
			(net 151 "unconnected-(J1-Pad147)")
			(pinfunction "147")
			(pintype "passive+no_connect")
		)
		(pad "148" smd rect
			(at 40.173 -1.301)
			(size 0.35 2.5)
			(layers "B.Cu" "B.Mask")
			(net 152 "unconnected-(J1-Pad148)")
			(pinfunction "148")
			(pintype "passive+no_connect")
		)
		(pad "149" smd rect
			(at 40.423 -1.301)
			(size 0.35 2.5)
			(layers "F.Cu" "F.Mask")
			(net 153 "unconnected-(J1-Pad149)")
			(pinfunction "149")
			(pintype "passive+no_connect")
		)
		(pad "150" smd rect
			(at 40.673 -1.301)
			(size 0.35 2.5)
			(layers "B.Cu" "B.Mask")
			(net 154 "unconnected-(J1-Pad150)")
			(pinfunction "150")
			(pintype "passive+no_connect")
		)
		(pad "151" smd rect
			(at 40.923 -1.301)
			(size 0.35 2.5)
			(layers "F.Cu" "F.Mask")
			(net 155 "unconnected-(J1-Pad151)")
			(pinfunction "151")
			(pintype "passive+no_connect")
		)
		(pad "152" smd rect
			(at 41.173 -1.301)
			(size 0.35 2.5)
			(layers "B.Cu" "B.Mask")
			(net 156 "unconnected-(J1-Pad152)")
			(pinfunction "152")
			(pintype "passive+no_connect")
		)
		(pad "153" smd rect
			(at 41.423 -1.301)
			(size 0.35 2.5)
			(layers "F.Cu" "F.Mask")
			(net 157 "unconnected-(J1-Pad153)")
			(pinfunction "153")
			(pintype "passive+no_connect")
		)
		(pad "154" smd rect
			(at 41.673 -1.301)
			(size 0.35 2.5)
			(layers "B.Cu" "B.Mask")
			(net 1 "GND")
			(pinfunction "154")
			(pintype "passive")
		)
		(pad "155" smd rect
			(at 41.923 -1.301)
			(size 0.35 2.5)
			(layers "F.Cu" "F.Mask")
			(net 158 "unconnected-(J1-Pad155)")
			(pinfunction "155")
			(pintype "passive+no_connect")
		)
		(pad "156" smd rect
			(at 42.173 -1.301)
			(size 0.35 2.5)
			(layers "B.Cu" "B.Mask")
			(net 56 "CAI")
			(pinfunction "156")
			(pintype "passive")
		)
		(pad "157" smd rect
			(at 42.423 -1.301)
			(size 0.35 2.5)
			(layers "F.Cu" "F.Mask")
			(net 159 "unconnected-(J1-Pad157)")
			(pinfunction "157")
			(pintype "passive+no_connect")
		)
		(pad "158" smd rect
			(at 42.673 -1.301)
			(size 0.35 2.5)
			(layers "B.Cu" "B.Mask")
			(net 53 "ALERT_N")
			(pinfunction "158")
			(pintype "passive")
		)
		(pad "159" smd rect
			(at 42.923 -1.301)
			(size 0.35 2.5)
			(layers "F.Cu" "F.Mask")
			(net 160 "unconnected-(J1-Pad159)")
			(pinfunction "159")
			(pintype "passive+no_connect")
		)
		(pad "160" smd rect
			(at 43.173 -1.301)
			(size 0.35 2.5)
			(layers "B.Cu" "B.Mask")
			(net 57 "MIR")
			(pinfunction "160")
			(pintype "passive")
		)
		(pad "161" smd rect
			(at 43.423 -1.301)
			(size 0.35 2.5)
			(layers "F.Cu" "F.Mask")
			(net 1 "GND")
			(pinfunction "161")
			(pintype "passive")
		)
		(pad "162" smd rect
			(at 43.673 -1.301)
			(size 0.35 2.5)
			(layers "B.Cu" "B.Mask")
			(net 17 "CS_N")
			(pinfunction "162")
			(pintype "passive")
		)
		(pad "163" smd rect
			(at 43.923 -1.301)
			(size 0.35 2.5)
			(layers "F.Cu" "F.Mask")
			(net 34 "CA12")
			(pinfunction "163")
			(pintype "passive")
		)
		(pad "164" smd rect
			(at 44.173 -1.301)
			(size 0.35 2.5)
			(layers "B.Cu" "B.Mask")
			(net 39 "TDQS_N")
			(pinfunction "164")
			(pintype "passive")
		)
		(pad "165" smd rect
			(at 44.423 -1.301)
			(size 0.35 2.5)
			(layers "F.Cu" "F.Mask")
			(net 32 "CA10")
			(pinfunction "165")
			(pintype "passive")
		)
		(pad "166" smd rect
			(at 44.673 -1.301)
			(size 0.35 2.5)
			(layers "B.Cu" "B.Mask")
			(net 37 "TDQS_P")
			(pinfunction "166")
			(pintype "passive")
		)
		(pad "167" smd rect
			(at 44.923 -1.301)
			(size 0.35 2.5)
			(layers "F.Cu" "F.Mask")
			(net 43 "CA8")
			(pinfunction "167")
			(pintype "passive")
		)
		(pad "168" smd rect
			(at 45.173 -1.301)
			(size 0.35 2.5)
			(layers "B.Cu" "B.Mask")
			(net 1 "GND")
			(pinfunction "168")
			(pintype "passive")
		)
		(pad "169" smd rect
			(at 45.423 -1.301)
			(size 0.35 2.5)
			(layers "F.Cu" "F.Mask")
			(net 40 "CA6")
			(pinfunction "169")
			(pintype "passive")
		)
		(pad "170" smd rect
			(at 45.673 -1.301)
			(size 0.35 2.5)
			(layers "B.Cu" "B.Mask")
			(net 161 "unconnected-(J1-Pad170)")
			(pinfunction "170")
			(pintype "passive+no_connect")
		)
		(pad "171" smd rect
			(at 45.923 -1.301)
			(size 0.35 2.5)
			(layers "F.Cu" "F.Mask")
			(net 46 "CA2")
			(pinfunction "171")
			(pintype "passive")
		)
		(pad "172" smd rect
			(at 46.173 -1.301)
			(size 0.35 2.5)
			(layers "B.Cu" "B.Mask")
			(net 162 "unconnected-(J1-Pad172)")
			(pinfunction "172")
			(pintype "passive+no_connect")
		)
		(pad "173" smd rect
			(at 46.423 -1.301)
			(size 0.35 2.5)
			(layers "F.Cu" "F.Mask")
			(net 44 "CLK_N")
			(pinfunction "173")
			(pintype "passive")
		)
		(pad "174" smd rect
			(at 46.673 -1.301)
			(size 0.35 2.5)
			(layers "B.Cu" "B.Mask")
			(net 163 "unconnected-(J1-Pad174)")
			(pinfunction "174")
			(pintype "passive+no_connect")
		)
		(pad "175" smd rect
			(at 46.923 -1.301)
			(size 0.35 2.5)
			(layers "F.Cu" "F.Mask")
			(net 42 "CLK_P")
			(pinfunction "175")
			(pintype "passive")
		)
		(pad "176" smd rect
			(at 47.173 -1.301)
			(size 0.35 2.5)
			(layers "B.Cu" "B.Mask")
			(net 164 "unconnected-(J1-Pad176)")
			(pinfunction "176")
			(pintype "passive+no_connect")
		)
		(pad "177" smd rect
			(at 47.423 -1.301)
			(size 0.35 2.5)
			(layers "F.Cu" "F.Mask")
			(net 1 "GND")
			(pinfunction "177")
			(pintype "passive")
		)
		(pad "178" smd rect
			(at 47.673 -1.301)
			(size 0.35 2.5)
			(layers "B.Cu" "B.Mask")
			(net 29 "DQ6")
			(pinfunction "178")
			(pintype "passive")
		)
		(pad "179" smd rect
			(at 47.923 -1.301)
			(size 0.35 2.5)
			(layers "F.Cu" "F.Mask")
			(net 48 "CA4")
			(pinfunction "179")
			(pintype "passive")
		)
		(pad "180" smd rect
			(at 48.173 -1.301)
			(size 0.35 2.5)
			(layers "B.Cu" "B.Mask")
			(net 30 "DQ5")
			(pinfunction "180")
			(pintype "passive")
		)
		(pad "181" smd rect
			(at 48.423 -1.301)
			(size 0.35 2.5)
			(layers "F.Cu" "F.Mask")
			(net 24 "CA0")
			(pinfunction "181")
			(pintype "passive")
		)
		(pad "182" smd rect
			(at 48.673 -1.301)
			(size 0.35 2.5)
			(layers "B.Cu" "B.Mask")
			(net 28 "DQ7")
			(pinfunction "182")
			(pintype "passive")
		)
		(pad "183" smd rect
			(at 48.923 -1.301)
			(size 0.35 2.5)
			(layers "F.Cu" "F.Mask")
			(net 33 "CA11")
			(pinfunction "183")
			(pintype "passive")
		)
		(pad "184" smd rect
			(at 49.173 -1.301)
			(size 0.35 2.5)
			(layers "B.Cu" "B.Mask")
			(net 1 "GND")
			(pinfunction "184")
			(pintype "passive")
		)
		(pad "185" smd rect
			(at 49.423 -1.301)
			(size 0.35 2.5)
			(layers "F.Cu" "F.Mask")
			(net 35 "CA13")
			(pinfunction "185")
			(pintype "passive")
		)
		(pad "186" smd rect
			(at 49.673 -1.301)
			(size 0.35 2.5)
			(layers "B.Cu" "B.Mask")
			(net 31 "DQ4")
			(pinfunction "186")
			(pintype "passive")
		)
		(pad "187" smd rect
			(at 49.923 -1.301)
			(size 0.35 2.5)
			(layers "F.Cu" "F.Mask")
			(net 45 "CA9")
			(pinfunction "187")
			(pintype "passive")
		)
		(pad "188" smd rect
			(at 50.173 -1.301)
			(size 0.35 2.5)
			(layers "B.Cu" "B.Mask")
			(net 165 "unconnected-(J1-Pad188)")
			(pinfunction "188")
			(pintype "passive+no_connect")
		)
		(pad "189" smd rect
			(at 50.423 -1.301)
			(size 0.35 2.5)
			(layers "F.Cu" "F.Mask")
			(net 41 "CA7")
			(pinfunction "189")
			(pintype "passive")
		)
		(pad "190" smd rect
			(at 50.673 -1.301)
			(size 0.35 2.5)
			(layers "B.Cu" "B.Mask")
			(net 166 "unconnected-(J1-Pad190)")
			(pinfunction "190")
			(pintype "passive+no_connect")
		)
		(pad "191" smd rect
			(at 50.923 -1.301)
			(size 0.35 2.5)
			(layers "F.Cu" "F.Mask")
			(net 47 "CA3")
			(pinfunction "191")
			(pintype "passive")
		)
		(pad "192" smd rect
			(at 51.173 -1.301)
			(size 0.35 2.5)
			(layers "B.Cu" "B.Mask")
			(net 23 "DQ1")
			(pinfunction "192")
			(pintype "passive")
		)
		(pad "193" smd rect
			(at 51.423 -1.301)
			(size 0.35 2.5)
			(layers "F.Cu" "F.Mask")
			(net 49 "CA5")
			(pinfunction "193")
			(pintype "passive")
		)
		(pad "194" smd rect
			(at 51.673 -1.301)
			(size 0.35 2.5)
			(layers "B.Cu" "B.Mask")
			(net 20 "DQ3")
			(pinfunction "194")
			(pintype "passive")
		)
		(pad "195" smd rect
			(at 51.923 -1.301)
			(size 0.35 2.5)
			(layers "F.Cu" "F.Mask")
			(net 1 "GND")
			(pinfunction "195")
			(pintype "passive")
		)
	)
)
